# S9S_MB_2U (Grand Teton) — schematic netlist excerpt (pin names and nets, part order shuffled) for the footprints in the layout excerpt that follows; sources: Cadence DE-HDL packaged netlist, KiCad conversion of 03242023_DA0F0TMBIJ0_F0T_Motherboard_J_brd_V01_OCP.brd

R3070  Q_RES  130 1% CHIP  pkg 0402LF  page 255 : A = LED_RST_PLTRST_N ; B = P3V3_AUX
C1540  Q_CAP_DIFFBUS  DIFF BUS_0.22UF 6.3V 20% X6S  pkg C0201  page 177 : \1\ = P5E_CPU1_PE3_TX_C_DN<3> ; \2\ = P5E_CPU1_PE3_TX_DN<3>
R579  Q_RES  33.2 1% CHIP  pkg 0402LF  page 241 : A = SMB_HOST_3V3AUX_SCL_R5 ; B = SMB_HOST_BMC_3V3AUX_SCL

(kicad_pcb
	(version 20260206)
	(generator "pcbnew")
	(generator_version "10.0")
	(general
		(thickness 1.6)
		(legacy_teardrops no)
	)
	(paper "A4")
	(title_block
		(title "03242023_DA0F0TMBIJ0_F0T_Motherboard_J_brd_V01_OCP.brd")
		(comment 1 "Grand Teton / footprints 3042-3044 of 6105")
	)
	(layers
		(0 "F.Cu" signal "TOP")
		(4 "In1.Cu" signal "GND")
		(6 "In2.Cu" signal "IN1")
		(8 "In3.Cu" signal "GND1")
		(10 "In4.Cu" signal "IN2")
		(12 "In5.Cu" signal "GND2")
		(14 "In6.Cu" signal "IN3")
		(16 "In7.Cu" signal "GND3")
		(18 "In8.Cu" signal "VCC")
		(20 "In9.Cu" signal "VCC1")
		(22 "In10.Cu" signal "GND4")
		(24 "In11.Cu" signal "IN4")
		(26 "In12.Cu" signal "GND5")
		(28 "In13.Cu" signal "IN5")
		(30 "In14.Cu" signal "GND6")
		(32 "In15.Cu" signal "IN6")
		(34 "In16.Cu" signal "GND7")
		(2 "B.Cu" signal "BOTTOM")
		(9 "F.Adhes" user "F.Adhesive")
		(11 "B.Adhes" user "B.Adhesive")
		(13 "F.Paste" user "Package Geometry/Pastemask Top")
		(15 "B.Paste" user "Package Geometry/Pastemask Bottom")
		(5 "F.SilkS" user "Ref Des/Silkscreen Top")
		(7 "B.SilkS" user "Ref Des/Silkscreen Bottom")
		(1 "F.Mask" user "Board Geometry/Soldermask Top")
		(3 "B.Mask" user "Board Geometry/Soldermask Bottom")
		(17 "Dwgs.User" user "User.Drawings")
		(19 "Cmts.User" user "User.Comments")
		(21 "Eco1.User" user "User.Eco1")
		(23 "Eco2.User" user "User.Eco2")
		(25 "Edge.Cuts" user "Board Geometry/Outline")
		(27 "Margin" user)
		(31 "F.CrtYd" user "Package Geometry/Place Bound Top")
		(29 "B.CrtYd" user "Package Geometry/Place Bound Bottom")
		(35 "F.Fab" user "Ref Des/Assembly Top")
		(33 "B.Fab" user "Ref Des/Assembly Bottom")
	)
	(footprint ""
		(layer "F.Cu")
		(at 4.699 -50.891948 180)
		(property "Reference" "R579"
			(at 0 0 180)
			(layer "F.SilkS")
			(hide yes)
			(effects
				(font
					(size 1.27 1.27)
				)
			)
		)
		(property "Value" ""
			(at 0 0 180)
			(layer "F.Fab")
			(effects
				(font
					(size 1.27 1.27)
				)
			)
		)
		(duplicate_pad_numbers_are_jumpers no)
		(fp_line
			(start 0.7874 0.4064)
			(end -0.7874 0.4064)
			(stroke
				(width 0.1524)
				(type default)
			)
			(layer "F.SilkS")
		)
		(fp_line
			(start 0.7874 -0.4064)
			(end 0.7874 0.4064)
			(stroke
				(width 0.1524)
				(type default)
			)
			(layer "F.SilkS")
		)
		(fp_line
			(start -0.7874 0.4064)
			(end -0.7874 -0.4064)
			(stroke
				(width 0.1524)
				(type default)
			)
			(layer "F.SilkS")
		)
		(fp_line
			(start -0.7874 -0.4064)
			(end 0.7874 -0.4064)
			(stroke
				(width 0.1524)
				(type default)
			)
			(layer "F.SilkS")
		)
		(fp_line
			(start 0.67945 0.3048)
			(end 0.120396 0.3048)
			(stroke
				(width 0.1)
				(type default)
			)
			(layer "F.Fab")
		)
		(fp_line
			(start 0.67945 -0.3048)
			(end 0.67945 0.3048)
			(stroke
				(width 0.1)
				(type default)
			)
			(layer "F.Fab")
		)
		(fp_line
			(start 0.12065 -0.2794)
			(end 0.12065 -0.3048)
			(stroke
				(width 0.1)
				(type default)
			)
			(layer "F.Fab")
		)
		(fp_line
			(start 0.12065 -0.3048)
			(end 0.67945 -0.3048)
			(stroke
				(width 0.1)
				(type default)
			)
			(layer "F.Fab")
		)
		(fp_line
			(start 0.120396 0.3048)
			(end 0.120396 0.2794)
			(stroke
				(width 0.1)
				(type default)
			)
			(layer "F.Fab")
		)
		(fp_line
			(start 0.120396 0.2794)
			(end -0.12065 0.2794)
			(stroke
				(width 0.1)
				(type default)
			)
			(layer "F.Fab")
		)
		(fp_line
			(start -0.12065 0.3048)
			(end -0.67945 0.3048)
			(stroke
				(width 0.1)
				(type default)
			)
			(layer "F.Fab")
		)
		(fp_line
			(start -0.12065 0.2794)
			(end -0.12065 0.3048)
			(stroke
				(width 0.1)
				(type default)
			)
			(layer "F.Fab")
		)
		(fp_line
			(start -0.12065 -0.2794)
			(end 0.12065 -0.2794)
			(stroke
				(width 0.1)
				(type default)
			)
			(layer "F.Fab")
		)
		(fp_line
			(start -0.12065 -0.305054)
			(end -0.12065 -0.2794)
			(stroke
				(width 0.1)
				(type default)
			)
			(layer "F.Fab")
		)
		(fp_line
			(start -0.67945 0.3048)
			(end -0.67945 -0.305054)
			(stroke
				(width 0.1)
				(type default)
			)
			(layer "F.Fab")
		)
		(fp_line
			(start -0.67945 -0.305054)
			(end -0.12065 -0.305054)
			(stroke
				(width 0.1)
				(type default)
			)
			(layer "F.Fab")
		)
		(pad "1" smd circle
			(at -0.40005 0 180)
			(size 0 0)
			(layers "F.Cu" "F.Mask" "F.Paste")
			(net "SMB_HOST_3V3AUX_SCL_R5")
		)
		(pad "2" smd circle
			(at 0.40005 0 180)
			(size 0 0)
			(layers "F.Cu" "F.Mask" "F.Paste")
			(net "SMB_HOST_BMC_3V3AUX_SCL")
		)
	)
	(footprint ""
		(layer "F.Cu")
		(at 158.234634 -408.517344 -90)
		(property "Reference" "C1540"
			(at 0 0 270)
			(layer "F.SilkS")
			(hide yes)
			(effects
				(font
					(size 1.27 1.27)
				)
			)
		)
		(property "Value" ""
			(at 0 0 270)
			(layer "F.Fab")
			(effects
				(font
					(size 1.27 1.27)
				)
			)
		)
		(duplicate_pad_numbers_are_jumpers no)
		(fp_line
			(start -0.299974 0.150114)
			(end -0.299974 -0.150114)
			(stroke
				(width 0.1)
				(type default)
			)
			(layer "F.Fab")
		)
		(fp_line
			(start 0.299974 0.150114)
			(end -0.299974 0.150114)
			(stroke
				(width 0.1)
				(type default)
			)
			(layer "F.Fab")
		)
		(fp_line
			(start -0.299974 -0.150114)
			(end 0.299974 -0.150114)
			(stroke
				(width 0.1)
				(type default)
			)
			(layer "F.Fab")
		)
		(fp_line
			(start 0.299974 -0.150114)
			(end 0.299974 0.150114)
			(stroke
				(width 0.1)
				(type default)
			)
			(layer "F.Fab")
		)
		(pad "1" smd rect
			(at -0.2667 0 270)
			(size 0.3048 0.381)
			(layers "F.Cu" "F.Mask" "F.Paste")
			(net "P5E_CPU1_PE3_TX_C_DN<3>")
		)
		(pad "2" smd rect
			(at 0.2667 0 270)
			(size 0.3048 0.381)
			(layers "F.Cu" "F.Mask" "F.Paste")
			(net "P5E_CPU1_PE3_TX_DN<3>")
		)
	)
	(footprint ""
		(layer "F.Cu")
		(at 83.730592 -65.068958 -90)
		(property "Reference" "R3070"
			(at 0 0 270)
			(layer "F.SilkS")
			(hide yes)
			(effects
				(font
					(size 1.27 1.27)
				)
			)
		)
		(property "Value" ""
			(at 0 0 270)
			(layer "F.Fab")
			(effects
				(font
					(size 1.27 1.27)
				)
			)
		)
		(duplicate_pad_numbers_are_jumpers no)
		(fp_line
			(start -0.7874 0.4064)
			(end -0.7874 -0.4064)
			(stroke
				(width 0.1524)
				(type default)
			)
			(layer "F.SilkS")
		)
		(fp_line
			(start 0.7874 0.4064)
			(end -0.7874 0.4064)
			(stroke
				(width 0.1524)
				(type default)
			)
			(layer "F.SilkS")
		)
		(fp_line
			(start -0.7874 -0.4064)
			(end 0.7874 -0.4064)
			(stroke
				(width 0.1524)
				(type default)
			)
			(layer "F.SilkS")
		)
		(fp_line
			(start 0.7874 -0.4064)
			(end 0.7874 0.4064)
			(stroke
				(width 0.1524)
				(type default)
			)
			(layer "F.SilkS")
		)
		(fp_line
			(start -0.67945 0.3048)
			(end -0.67945 -0.305054)
			(stroke
				(width 0.1)
				(type default)
			)
			(layer "F.Fab")
		)
		(fp_line
			(start -0.12065 0.3048)
			(end -0.67945 0.3048)
			(stroke
				(width 0.1)
				(type default)
			)
			(layer "F.Fab")
		)
		(fp_line
			(start 0.120396 0.3048)
			(end 0.120396 0.2794)
			(stroke
				(width 0.1)
				(type default)
			)
			(layer "F.Fab")
		)
		(fp_line
			(start 0.67945 0.3048)
			(end 0.120396 0.3048)
			(stroke
				(width 0.1)
				(type default)
			)
			(layer "F.Fab")
		)
		(fp_line
			(start -0.12065 0.2794)
			(end -0.12065 0.3048)
			(stroke
				(width 0.1)
				(type default)
			)
			(layer "F.Fab")
		)
		(fp_line
			(start 0.120396 0.2794)
			(end -0.12065 0.2794)
			(stroke
				(width 0.1)
				(type default)
			)
			(layer "F.Fab")
		)
		(fp_line
			(start -0.12065 -0.2794)
			(end 0.12065 -0.2794)
			(stroke
				(width 0.1)
				(type default)
			)
			(layer "F.Fab")
		)
		(fp_line
			(start 0.12065 -0.2794)
			(end 0.12065 -0.3048)
			(stroke
				(width 0.1)
				(type default)
			)
			(layer "F.Fab")
		)
		(fp_line
			(start 0.12065 -0.3048)
			(end 0.67945 -0.3048)
			(stroke
				(width 0.1)
				(type default)
			)
			(layer "F.Fab")
		)
		(fp_line
			(start 0.67945 -0.3048)
			(end 0.67945 0.3048)
			(stroke
				(width 0.1)
				(type default)
			)
			(layer "F.Fab")
		)
		(fp_line
			(start -0.67945 -0.305054)
			(end -0.12065 -0.305054)
			(stroke
				(width 0.1)
				(type default)
			)
			(layer "F.Fab")
		)
		(fp_line
			(start -0.12065 -0.305054)
			(end -0.12065 -0.2794)
			(stroke
				(width 0.1)
				(type default)
			)
			(layer "F.Fab")
		)
		(pad "1" smd circle
			(at -0.40005 0 270)
			(size 0 0)
			(layers "F.Cu" "F.Mask" "F.Paste")
			(net "LED_RST_PLTRST_N")
		)
		(pad "2" smd circle
			(at 0.40005 0 270)
			(size 0 0)
			(layers "F.Cu" "F.Mask" "F.Paste")
			(net "P3V3_AUX")
		)
	)
)
